(kicad_pcb
	(version 20241229)
	(generator "pcbnew")
	(generator_version "9.0")
	(general
		(thickness 1.599998)
		(legacy_teardrops no)
	)
	(paper "A4")
	(title_block
		(date "2023-02-12")
		(rev "1.1.5")
		(comment 9 "footprints 408-414 of 473")
	)
	(layers
		(0 "F.Cu" signal)
		(4 "In1.Cu" power "In1.GND")
		(6 "In2.Cu" signal)
		(8 "In3.Cu" power "In3.GND")
		(10 "In4.Cu" power "In4.VCC")
		(12 "In5.Cu" signal)
		(14 "In6.Cu" power "In6.VCC")
		(2 "B.Cu" signal)
		(9 "F.Adhes" user "F.Adhesive")
		(11 "B.Adhes" user "B.Adhesive")
		(13 "F.Paste" user)
		(15 "B.Paste" user)
		(5 "F.SilkS" user "F.Silkscreen")
		(7 "B.SilkS" user "B.Silkscreen")
		(1 "F.Mask" user)
		(3 "B.Mask" user)
		(17 "Dwgs.User" user "User.Drawings")
		(19 "Cmts.User" user "User.Comments")
		(21 "Eco1.User" user "User.Eco1")
		(23 "Eco2.User" user "User.Eco2")
		(25 "Edge.Cuts" user)
		(27 "Margin" user)
		(31 "F.CrtYd" user "F.Courtyard")
		(29 "B.CrtYd" user "B.Courtyard")
		(35 "F.Fab" user)
		(33 "B.Fab" user)
	)
	(footprint "antmicro-footprints:C_0402_1005Metric"
		(layer "B.Cu")
		(at 160.536328 89.797157)
		(descr "Capacitor SMD 0402")
		(tags "capacitor SMD 0402")
		(property "Reference" "C6"
			(at 0.763672 -0.497157 180)
			(layer "B.SilkS")
			(effects
				(font
					(size 0.7 0.7)
					(thickness 0.15)
				)
				(justify left bottom mirror)
			)
		)
		(property "Value" "C_100n_6V3_0402"
			(at 0 -1.4 180)
			(layer "B.Fab")
			(effects
				(font
					(size 0.7 0.7)
					(thickness 0.15)
				)
				(justify left bottom mirror)
			)
		)
		(property "Description" " "
			(at 0 0 0)
			(layer "F.Fab")
			(hide yes)
			(effects
				(font
					(size 1.27 1.27)
					(thickness 0.15)
				)
			)
		)
		(property "Author" "Antmicro"
			(at 0 0 0)
			(layer "B.Fab")
			(hide yes)
			(effects
				(font
					(size 1 1)
					(thickness 0.15)
				)
				(justify mirror)
			)
		)
		(property "Dielectric" ""
			(at 0 0 0)
			(layer "B.Fab")
			(hide yes)
			(effects
				(font
					(size 1 1)
					(thickness 0.15)
				)
				(justify mirror)
			)
		)
		(property "License" "Apache-2.0"
			(at 0 0 0)
			(layer "B.Fab")
			(hide yes)
			(effects
				(font
					(size 1 1)
					(thickness 0.15)
				)
				(justify mirror)
			)
		)
		(property "MPN" "0402X104K6R3CT"
			(at 0 0 0)
			(layer "B.Fab")
			(hide yes)
			(effects
				(font
					(size 1 1)
					(thickness 0.15)
				)
				(justify mirror)
			)
		)
		(property "Manufacturer" "Walsin"
			(at 0 0 0)
			(layer "B.Fab")
			(hide yes)
			(effects
				(font
					(size 1 1)
					(thickness 0.15)
				)
				(justify mirror)
			)
		)
		(property "Val" "100n"
			(at 0 0 0)
			(layer "B.Fab")
			(hide yes)
			(effects
				(font
					(size 1 1)
					(thickness 0.15)
				)
				(justify mirror)
			)
		)
		(property "Voltage" ""
			(at 0 0 0)
			(layer "B.Fab")
			(hide yes)
			(effects
				(font
					(size 1 1)
					(thickness 0.15)
				)
				(justify mirror)
			)
		)
		(sheetname "FPGA Banks")
		(sheetfile "fpga-banks.kicad_sch")
		(attr smd)
		(fp_rect
			(start -0.94 0.47)
			(end 0.94 -0.47)
			(stroke
				(width 0.05)
				(type solid)
			)
			(fill no)
			(layer "B.CrtYd")
		)
		(fp_rect
			(start -0.499 0.249)
			(end 0.499 -0.249)
			(stroke
				(width 0.15)
				(type solid)
			)
			(fill no)
			(layer "B.Fab")
		)
		(pad "1" smd roundrect
			(at -0.484 0)
			(size 0.59 0.64)
			(layers "B.Cu" "B.Mask" "B.Paste")
			(roundrect_rratio 0.25)
			(net 5 "GND")
			(pintype "passive")
		)
		(pad "2" smd roundrect
			(at 0.484 0)
			(size 0.59 0.64)
			(layers "B.Cu" "B.Mask" "B.Paste")
			(roundrect_rratio 0.25)
			(net 510 "VREF_34")
			(pintype "passive")
		)
	)
	(footprint "antmicro-footprints:C_0402_1005Metric"
		(layer "B.Cu")
		(at 169.036328 90.097157 90)
		(descr "Capacitor SMD 0402")
		(tags "capacitor SMD 0402")
		(property "Reference" "C7"
			(at 2.297157 0.463672 270)
			(layer "B.SilkS")
			(effects
				(font
					(size 0.7 0.7)
					(thickness 0.15)
				)
				(justify left bottom mirror)
			)
		)
		(property "Value" "C_100n_6V3_0402"
			(at 0 -1.4 270)
			(layer "B.Fab")
			(effects
				(font
					(size 0.7 0.7)
					(thickness 0.15)
				)
				(justify left bottom mirror)
			)
		)
		(property "Description" " "
			(at 0 0 90)
			(layer "F.Fab")
			(hide yes)
			(effects
				(font
					(size 1.27 1.27)
					(thickness 0.15)
				)
			)
		)
		(property "Author" "Antmicro"
			(at 259.133485 -78.939171 0)
			(layer "B.Fab")
			(hide yes)
			(effects
				(font
					(size 1 1)
					(thickness 0.15)
				)
				(justify mirror)
			)
		)
		(property "Dielectric" ""
			(at 259.133485 -78.939171 0)
			(layer "B.Fab")
			(hide yes)
			(effects
				(font
					(size 1 1)
					(thickness 0.15)
				)
				(justify mirror)
			)
		)
		(property "License" "Apache-2.0"
			(at 259.133485 -78.939171 0)
			(layer "B.Fab")
			(hide yes)
			(effects
				(font
					(size 1 1)
					(thickness 0.15)
				)
				(justify mirror)
			)
		)
		(property "MPN" "0402X104K6R3CT"
			(at 259.133485 -78.939171 0)
			(layer "B.Fab")
			(hide yes)
			(effects
				(font
					(size 1 1)
					(thickness 0.15)
				)
				(justify mirror)
			)
		)
		(property "Manufacturer" "Walsin"
			(at 259.133485 -78.939171 0)
			(layer "B.Fab")
			(hide yes)
			(effects
				(font
					(size 1 1)
					(thickness 0.15)
				)
				(justify mirror)
			)
		)
		(property "Val" "100n"
			(at 259.133485 -78.939171 0)
			(layer "B.Fab")
			(hide yes)
			(effects
				(font
					(size 1 1)
					(thickness 0.15)
				)
				(justify mirror)
			)
		)
		(property "Voltage" ""
			(at 259.133485 -78.939171 0)
			(layer "B.Fab")
			(hide yes)
			(effects
				(font
					(size 1 1)
					(thickness 0.15)
				)
				(justify mirror)
			)
		)
		(sheetname "FPGA Banks")
		(sheetfile "fpga-banks.kicad_sch")
		(attr smd)
		(fp_rect
			(start -0.94 0.47)
			(end 0.94 -0.47)
			(stroke
				(width 0.05)
				(type solid)
			)
			(fill no)
			(layer "B.CrtYd")
		)
		(fp_rect
			(start -0.499 0.249)
			(end 0.499 -0.249)
			(stroke
				(width 0.15)
				(type solid)
			)
			(fill no)
			(layer "B.Fab")
		)
		(pad "1" smd roundrect
			(at -0.484 0 90)
			(size 0.59 0.64)
			(layers "B.Cu" "B.Mask" "B.Paste")
			(roundrect_rratio 0.25)
			(net 5 "GND")
			(pintype "passive")
		)
		(pad "2" smd roundrect
			(at 0.484 0 90)
			(size 0.59 0.64)
			(layers "B.Cu" "B.Mask" "B.Paste")
			(roundrect_rratio 0.25)
			(net 510 "VREF_34")
			(pintype "passive")
		)
	)
	(footprint "antmicro-footprints:R_0603_1608Metric"
		(layer "B.Cu")
		(at 156.936328 90.397157 90)
		(descr "Resistor SMD 0603")
		(tags "resistor SMD 0603")
		(property "Reference" "R5"
			(at 0.797157 -0.636328 270)
			(layer "B.SilkS")
			(effects
				(font
					(size 0.7 0.7)
					(thickness 0.15)
				)
				(justify left bottom mirror)
			)
		)
		(property "Value" "R_1k_0603"
			(at 0 -1.6 270)
			(layer "B.Fab")
			(effects
				(font
					(size 0.7 0.7)
					(thickness 0.15)
				)
				(justify left bottom mirror)
			)
		)
		(property "Description" "1k resistor in 0603 package with 1% tolerance"
			(at 0 0 90)
			(layer "F.Fab")
			(hide yes)
			(effects
				(font
					(size 1.27 1.27)
					(thickness 0.15)
				)
			)
		)
		(property "Author" "Antmicro"
			(at 247.333485 -66.539171 0)
			(layer "B.Fab")
			(hide yes)
			(effects
				(font
					(size 1 1)
					(thickness 0.15)
				)
				(justify mirror)
			)
		)
		(property "License" "Apache-2.0"
			(at 247.333485 -66.539171 0)
			(layer "B.Fab")
			(hide yes)
			(effects
				(font
					(size 1 1)
					(thickness 0.15)
				)
				(justify mirror)
			)
		)
		(property "MPN" "CR0603-FX-1001ELF"
			(at 247.333485 -66.539171 0)
			(layer "B.Fab")
			(hide yes)
			(effects
				(font
					(size 1 1)
					(thickness 0.15)
				)
				(justify mirror)
			)
		)
		(property "Manufacturer" "Bourns"
			(at 247.333485 -66.539171 0)
			(layer "B.Fab")
			(hide yes)
			(effects
				(font
					(size 1 1)
					(thickness 0.15)
				)
				(justify mirror)
			)
		)
		(property "Tolerance" "1%"
			(at 247.333485 -66.539171 0)
			(layer "B.Fab")
			(hide yes)
			(effects
				(font
					(size 1 1)
					(thickness 0.15)
				)
				(justify mirror)
			)
		)
		(property "Val" "1k"
			(at 247.333485 -66.539171 0)
			(layer "B.Fab")
			(hide yes)
			(effects
				(font
					(size 1 1)
					(thickness 0.15)
				)
				(justify mirror)
			)
		)
		(sheetname "FPGA Banks")
		(sheetfile "fpga-banks.kicad_sch")
		(attr smd)
		(fp_line
			(start -0.3 -0.3)
			(end 0.3 -0.3)
			(stroke
				(width 0.15)
				(type solid)
			)
			(layer "B.SilkS")
		)
		(fp_line
			(start -0.3 0.3)
			(end 0.3 0.3)
			(stroke
				(width 0.15)
				(type solid)
			)
			(layer "B.SilkS")
		)
		(fp_rect
			(start -1.25 0.7)
			(end 1.25 -0.7)
			(stroke
				(width 0.05)
				(type solid)
			)
			(fill no)
			(layer "B.CrtYd")
		)
		(fp_rect
			(start -0.8 0.4)
			(end 0.8 -0.4)
			(stroke
				(width 0.15)
				(type solid)
			)
			(fill no)
			(layer "B.Fab")
		)
		(pad "1" smd roundrect
			(at -0.7 0 90)
			(size 0.6 0.8)
			(layers "B.Cu" "B.Mask" "B.Paste")
			(roundrect_rratio 0.2)
			(net 66 "VDDQ")
			(pintype "passive")
		)
		(pad "2" smd roundrect
			(at 0.7 0 90)
			(size 0.6 0.8)
			(layers "B.Cu" "B.Mask" "B.Paste")
			(roundrect_rratio 0.2)
			(net 510 "VREF_34")
			(pintype "passive")
		)
	)
	(footprint "antmicro-footprints:R_0402_1005Metric"
		(layer "B.Cu")
		(at 196.686328 94.520008 90)
		(descr "Resistor SMD 0402")
		(tags "resistor SMD 0402")
		(property "Reference" "R75"
			(at 2.920008 0.413672 270)
			(layer "B.SilkS")
			(effects
				(font
					(size 0.7 0.7)
					(thickness 0.15)
				)
				(justify left bottom mirror)
			)
		)
		(property "Value" "R_10k2_0402"
			(at 0 -1.4 270)
			(layer "B.Fab")
			(effects
				(font
					(size 0.7 0.7)
					(thickness 0.15)
				)
				(justify left bottom mirror)
			)
		)
		(property "Description" "10k2 resistor in 0402 package with 1% tolerance"
			(at 0 0 90)
			(layer "F.Fab")
			(hide yes)
			(effects
				(font
					(size 1.27 1.27)
					(thickness 0.15)
				)
			)
		)
		(property "Author" "Antmicro"
			(at 291.206336 -102.16632 0)
			(layer "B.Fab")
			(hide yes)
			(effects
				(font
					(size 1 1)
					(thickness 0.15)
				)
				(justify mirror)
			)
		)
		(property "License" "Apache-2.0"
			(at 291.206336 -102.16632 0)
			(layer "B.Fab")
			(hide yes)
			(effects
				(font
					(size 1 1)
					(thickness 0.15)
				)
				(justify mirror)
			)
		)
		(property "MPN" "CR0402-FX-1022GLF"
			(at 291.206336 -102.16632 0)
			(layer "B.Fab")
			(hide yes)
			(effects
				(font
					(size 1 1)
					(thickness 0.15)
				)
				(justify mirror)
			)
		)
		(property "Manufacturer" "Bourns"
			(at 291.206336 -102.16632 0)
			(layer "B.Fab")
			(hide yes)
			(effects
				(font
					(size 1 1)
					(thickness 0.15)
				)
				(justify mirror)
			)
		)
		(property "Tolerance" "1%"
			(at 291.206336 -102.16632 0)
			(layer "B.Fab")
			(hide yes)
			(effects
				(font
					(size 1 1)
					(thickness 0.15)
				)
				(justify mirror)
			)
		)
		(property "Val" "10k2"
			(at 291.206336 -102.16632 0)
			(layer "B.Fab")
			(hide yes)
			(effects
				(font
					(size 1 1)
					(thickness 0.15)
				)
				(justify mirror)
			)
		)
		(sheetname "Ethernet")
		(sheetfile "ethernet.kicad_sch")
		(attr exclude_from_pos_files exclude_from_bom dnp)
		(fp_rect
			(start -0.93 0.47)
			(end 0.93 -0.47)
			(stroke
				(width 0.05)
				(type solid)
			)
			(fill no)
			(layer "B.CrtYd")
		)
		(fp_rect
			(start -0.5 0.25)
			(end 0.5 -0.25)
			(stroke
				(width 0.15)
				(type solid)
			)
			(fill no)
			(layer "B.Fab")
		)
		(pad "1" smd roundrect
			(at -0.485 0 90)
			(size 0.59 0.64)
			(layers "B.Cu" "B.Mask" "B.Paste")
			(roundrect_rratio 0.25)
			(net 23 "ETH_RXD1")
			(pintype "passive")
		)
		(pad "2" smd roundrect
			(at 0.485 0 90)
			(size 0.59 0.64)
			(layers "B.Cu" "B.Mask" "B.Paste")
			(roundrect_rratio 0.25)
			(net 459 "3V3_SYS")
			(pintype "passive")
		)
	)
	(footprint "antmicro-footprints:R_0402_1005Metric"
		(layer "B.Cu")
		(at 197.686328 94.020008 90)
		(descr "Resistor SMD 0402")
		(tags "resistor SMD 0402")
		(property "Reference" "R76"
			(at 3.020008 0.413672 270)
			(layer "B.SilkS")
			(effects
				(font
					(size 0.7 0.7)
					(thickness 0.15)
				)
				(justify left bottom mirror)
			)
		)
		(property "Value" "R_10k2_0402"
			(at 0 -1.4 270)
			(layer "B.Fab")
			(effects
				(font
					(size 0.7 0.7)
					(thickness 0.15)
				)
				(justify left bottom mirror)
			)
		)
		(property "Description" "10k2 resistor in 0402 package with 1% tolerance"
			(at 0 0 90)
			(layer "F.Fab")
			(hide yes)
			(effects
				(font
					(size 1.27 1.27)
					(thickness 0.15)
				)
			)
		)
		(property "Author" "Antmicro"
			(at 291.706336 -103.66632 0)
			(layer "B.Fab")
			(hide yes)
			(effects
				(font
					(size 1 1)
					(thickness 0.15)
				)
				(justify mirror)
			)
		)
		(property "License" "Apache-2.0"
			(at 291.706336 -103.66632 0)
			(layer "B.Fab")
			(hide yes)
			(effects
				(font
					(size 1 1)
					(thickness 0.15)
				)
				(justify mirror)
			)
		)
		(property "MPN" "CR0402-FX-1022GLF"
			(at 291.706336 -103.66632 0)
			(layer "B.Fab")
			(hide yes)
			(effects
				(font
					(size 1 1)
					(thickness 0.15)
				)
				(justify mirror)
			)
		)
		(property "Manufacturer" "Bourns"
			(at 291.706336 -103.66632 0)
			(layer "B.Fab")
			(hide yes)
			(effects
				(font
					(size 1 1)
					(thickness 0.15)
				)
				(justify mirror)
			)
		)
		(property "Tolerance" "1%"
			(at 291.706336 -103.66632 0)
			(layer "B.Fab")
			(hide yes)
			(effects
				(font
					(size 1 1)
					(thickness 0.15)
				)
				(justify mirror)
			)
		)
		(property "Val" "10k2"
			(at 291.706336 -103.66632 0)
			(layer "B.Fab")
			(hide yes)
			(effects
				(font
					(size 1 1)
					(thickness 0.15)
				)
				(justify mirror)
			)
		)
		(sheetname "Ethernet")
		(sheetfile "ethernet.kicad_sch")
		(attr smd)
		(fp_rect
			(start -0.93 0.47)
			(end 0.93 -0.47)
			(stroke
				(width 0.05)
				(type solid)
			)
			(fill no)
			(layer "B.CrtYd")
		)
		(fp_rect
			(start -0.5 0.25)
			(end 0.5 -0.25)
			(stroke
				(width 0.15)
				(type solid)
			)
			(fill no)
			(layer "B.Fab")
		)
		(pad "1" smd roundrect
			(at -0.485 0 90)
			(size 0.59 0.64)
			(layers "B.Cu" "B.Mask" "B.Paste")
			(roundrect_rratio 0.25)
			(net 37 "ETH_RXD2")
			(pintype "passive")
		)
		(pad "2" smd roundrect
			(at 0.485 0 90)
			(size 0.59 0.64)
			(layers "B.Cu" "B.Mask" "B.Paste")
			(roundrect_rratio 0.25)
			(net 459 "3V3_SYS")
			(pintype "passive")
		)
	)
	(footprint "antmicro-footprints:R_0402_1005Metric"
		(layer "B.Cu")
		(at 199.786328 93.220008 90)
		(descr "Resistor SMD 0402")
		(tags "resistor SMD 0402")
		(property "Reference" "R77"
			(at 1.120008 1.313672 270)
			(layer "B.SilkS")
			(effects
				(font
					(size 0.7 0.7)
					(thickness 0.15)
				)
				(justify left bottom mirror)
			)
		)
		(property "Value" "R_10k2_0402"
			(at 0 -1.4 270)
			(layer "B.Fab")
			(effects
				(font
					(size 0.7 0.7)
					(thickness 0.15)
				)
				(justify left bottom mirror)
			)
		)
		(property "Description" "10k2 resistor in 0402 package with 1% tolerance"
			(at 0 0 90)
			(layer "F.Fab")
			(hide yes)
			(effects
				(font
					(size 1.27 1.27)
					(thickness 0.15)
				)
			)
		)
		(property "Author" "Antmicro"
			(at 293.006336 -106.56632 0)
			(layer "B.Fab")
			(hide yes)
			(effects
				(font
					(size 1 1)
					(thickness 0.15)
				)
				(justify mirror)
			)
		)
		(property "License" "Apache-2.0"
			(at 293.006336 -106.56632 0)
			(layer "B.Fab")
			(hide yes)
			(effects
				(font
					(size 1 1)
					(thickness 0.15)
				)
				(justify mirror)
			)
		)
		(property "MPN" "CR0402-FX-1022GLF"
			(at 293.006336 -106.56632 0)
			(layer "B.Fab")
			(hide yes)
			(effects
				(font
					(size 1 1)
					(thickness 0.15)
				)
				(justify mirror)
			)
		)
		(property "Manufacturer" "Bourns"
			(at 293.006336 -106.56632 0)
			(layer "B.Fab")
			(hide yes)
			(effects
				(font
					(size 1 1)
					(thickness 0.15)
				)
				(justify mirror)
			)
		)
		(property "Tolerance" "1%"
			(at 293.006336 -106.56632 0)
			(layer "B.Fab")
			(hide yes)
			(effects
				(font
					(size 1 1)
					(thickness 0.15)
				)
				(justify mirror)
			)
		)
		(property "Val" "10k2"
			(at 293.006336 -106.56632 0)
			(layer "B.Fab")
			(hide yes)
			(effects
				(font
					(size 1 1)
					(thickness 0.15)
				)
				(justify mirror)
			)
		)
		(sheetname "Ethernet")
		(sheetfile "ethernet.kicad_sch")
		(attr smd)
		(fp_rect
			(start -0.93 0.47)
			(end 0.93 -0.47)
			(stroke
				(width 0.05)
				(type solid)
			)
			(fill no)
			(layer "B.CrtYd")
		)
		(fp_rect
			(start -0.5 0.25)
			(end 0.5 -0.25)
			(stroke
				(width 0.15)
				(type solid)
			)
			(fill no)
			(layer "B.Fab")
		)
		(pad "1" smd roundrect
			(at -0.485 0 90)
			(size 0.59 0.64)
			(layers "B.Cu" "B.Mask" "B.Paste")
			(roundrect_rratio 0.25)
			(net 33 "ETH_RXD3")
			(pintype "passive")
		)
		(pad "2" smd roundrect
			(at 0.485 0 90)
			(size 0.59 0.64)
			(layers "B.Cu" "B.Mask" "B.Paste")
			(roundrect_rratio 0.25)
			(net 459 "3V3_SYS")
			(pintype "passive")
		)
	)
	(footprint "antmicro-footprints:R_0402_1005Metric"
		(layer "B.Cu")
		(at 194.686328 95.720008 90)
		(descr "Resistor SMD 0402")
		(tags "resistor SMD 0402")
		(property "Reference" "R78"
			(at 2.920008 0.413672 270)
			(layer "B.SilkS")
			(effects
				(font
					(size 0.7 0.7)
					(thickness 0.15)
				)
				(justify left bottom mirror)
			)
		)
		(property "Value" "R_10k2_0402"
			(at 0 -1.4 270)
			(layer "B.Fab")
			(effects
				(font
					(size 0.7 0.7)
					(thickness 0.15)
				)
				(justify left bottom mirror)
			)
		)
		(property "Description" "10k2 resistor in 0402 package with 1% tolerance"
			(at 0 0 90)
			(layer "F.Fab")
			(hide yes)
			(effects
				(font
					(size 1.27 1.27)
					(thickness 0.15)
				)
			)
		)
		(property "Author" "Antmicro"
			(at 290.406336 -98.96632 0)
			(layer "B.Fab")
			(hide yes)
			(effects
				(font
					(size 1 1)
					(thickness 0.15)
				)
				(justify mirror)
			)
		)
		(property "License" "Apache-2.0"
			(at 290.406336 -98.96632 0)
			(layer "B.Fab")
			(hide yes)
			(effects
				(font
					(size 1 1)
					(thickness 0.15)
				)
				(justify mirror)
			)
		)
		(property "MPN" "CR0402-FX-1022GLF"
			(at 290.406336 -98.96632 0)
			(layer "B.Fab")
			(hide yes)
			(effects
				(font
					(size 1 1)
					(thickness 0.15)
				)
				(justify mirror)
			)
		)
		(property "Manufacturer" "Bourns"
			(at 290.406336 -98.96632 0)
			(layer "B.Fab")
			(hide yes)
			(effects
				(font
					(size 1 1)
					(thickness 0.15)
				)
				(justify mirror)
			)
		)
		(property "Tolerance" "1%"
			(at 290.406336 -98.96632 0)
			(layer "B.Fab")
			(hide yes)
			(effects
				(font
					(size 1 1)
					(thickness 0.15)
				)
				(justify mirror)
			)
		)
		(property "Val" "10k2"
			(at 290.406336 -98.96632 0)
			(layer "B.Fab")
			(hide yes)
			(effects
				(font
					(size 1 1)
					(thickness 0.15)
				)
				(justify mirror)
			)
		)
		(sheetname "Ethernet")
		(sheetfile "ethernet.kicad_sch")
		(attr exclude_from_pos_files exclude_from_bom dnp)
		(fp_rect
			(start -0.93 0.47)
			(end 0.93 -0.47)
			(stroke
				(width 0.05)
				(type solid)
			)
			(fill no)
			(layer "B.CrtYd")
		)
		(fp_rect
			(start -0.5 0.25)
			(end 0.5 -0.25)
			(stroke
				(width 0.15)
				(type solid)
			)
			(fill no)
			(layer "B.Fab")
		)
		(pad "1" smd roundrect
			(at -0.485 0 90)
			(size 0.59 0.64)
			(layers "B.Cu" "B.Mask" "B.Paste")
			(roundrect_rratio 0.25)
			(net 34 "ETH_RX_DV")
			(pintype "passive")
		)
		(pad "2" smd roundrect
			(at 0.485 0 90)
			(size 0.59 0.64)
			(layers "B.Cu" "B.Mask" "B.Paste")
			(roundrect_rratio 0.25)
			(net 459 "3V3_SYS")
			(pintype "passive")
		)
	)
)
